# S9S_MB_2U (Grand Teton) — schematic netlist excerpt (pin names and nets, part order shuffled) for the footprints in the layout excerpt that follows; sources: Cadence DE-HDL packaged netlist, KiCad conversion of 03242023_DA0F0TMBIJ0_F0T_Motherboard_J_brd_V01_OCP.brd

C970  Q_CAP  10UF 6.3V 20% X6S  pkg C0402  page 74 : A = PVCCIN_CPU0 ; B = GND
C1043  Q_CAP  22UF 4V 20% X6S  pkg C0402  page 74 : A = PVCCIN_CPU0 ; B = GND
C1543  Q_CAP_DIFFBUS  DIFF BUS_0.22UF 6.3V 20% X6S  pkg C0201  page 177 : \1\ = P5E_CPU1_PE3_TX_C_DP<2> ; \2\ = P5E_CPU1_PE3_TX_DP<2>

(kicad_pcb
	(version 20260206)
	(generator "pcbnew")
	(generator_version "10.0")
	(general
		(thickness 1.6)
		(legacy_teardrops no)
	)
	(paper "A4")
	(title_block
		(title "03242023_DA0F0TMBIJ0_F0T_Motherboard_J_brd_V01_OCP.brd")
		(comment 1 "Grand Teton / footprints 1608-1610 of 6105")
	)
	(layers
		(0 "F.Cu" signal "TOP")
		(4 "In1.Cu" signal "GND")
		(6 "In2.Cu" signal "IN1")
		(8 "In3.Cu" signal "GND1")
		(10 "In4.Cu" signal "IN2")
		(12 "In5.Cu" signal "GND2")
		(14 "In6.Cu" signal "IN3")
		(16 "In7.Cu" signal "GND3")
		(18 "In8.Cu" signal "VCC")
		(20 "In9.Cu" signal "VCC1")
		(22 "In10.Cu" signal "GND4")
		(24 "In11.Cu" signal "IN4")
		(26 "In12.Cu" signal "GND5")
		(28 "In13.Cu" signal "IN5")
		(30 "In14.Cu" signal "GND6")
		(32 "In15.Cu" signal "IN6")
		(34 "In16.Cu" signal "GND7")
		(2 "B.Cu" signal "BOTTOM")
		(9 "F.Adhes" user "F.Adhesive")
		(11 "B.Adhes" user "B.Adhesive")
		(13 "F.Paste" user "Package Geometry/Pastemask Top")
		(15 "B.Paste" user "Package Geometry/Pastemask Bottom")
		(5 "F.SilkS" user "Ref Des/Silkscreen Top")
		(7 "B.SilkS" user "Ref Des/Silkscreen Bottom")
		(1 "F.Mask" user "Board Geometry/Soldermask Top")
		(3 "B.Mask" user "Board Geometry/Soldermask Bottom")
		(17 "Dwgs.User" user "User.Drawings")
		(19 "Cmts.User" user "User.Comments")
		(21 "Eco1.User" user "User.Eco1")
		(23 "Eco2.User" user "User.Eco2")
		(25 "Edge.Cuts" user "Board Geometry/Outline")
		(27 "Margin" user)
		(31 "F.CrtYd" user "Package Geometry/Place Bound Top")
		(29 "B.CrtYd" user "Package Geometry/Place Bound Bottom")
		(35 "F.Fab" user "Ref Des/Assembly Top")
		(33 "B.Fab" user "Ref Des/Assembly Bottom")
	)
	(footprint ""
		(layer "F.Cu")
		(at 162.212274 -408.517344 -90)
		(property "Reference" "C1543"
			(at 0 0 270)
			(layer "F.SilkS")
			(hide yes)
			(effects
				(font
					(size 1.27 1.27)
				)
			)
		)
		(property "Value" ""
			(at 0 0 270)
			(layer "F.Fab")
			(effects
				(font
					(size 1.27 1.27)
				)
			)
		)
		(duplicate_pad_numbers_are_jumpers no)
		(fp_line
			(start -0.299974 0.150114)
			(end -0.299974 -0.150114)
			(stroke
				(width 0.1)
				(type default)
			)
			(layer "F.Fab")
		)
		(fp_line
			(start 0.299974 0.150114)
			(end -0.299974 0.150114)
			(stroke
				(width 0.1)
				(type default)
			)
			(layer "F.Fab")
		)
		(fp_line
			(start -0.299974 -0.150114)
			(end 0.299974 -0.150114)
			(stroke
				(width 0.1)
				(type default)
			)
			(layer "F.Fab")
		)
		(fp_line
			(start 0.299974 -0.150114)
			(end 0.299974 0.150114)
			(stroke
				(width 0.1)
				(type default)
			)
			(layer "F.Fab")
		)
		(pad "1" smd rect
			(at -0.2667 0 270)
			(size 0.3048 0.381)
			(layers "F.Cu" "F.Mask" "F.Paste")
			(net "P5E_CPU1_PE3_TX_C_DP<2>")
		)
		(pad "2" smd rect
			(at 0.2667 0 270)
			(size 0.3048 0.381)
			(layers "F.Cu" "F.Mask" "F.Paste")
			(net "P5E_CPU1_PE3_TX_DP<2>")
		)
	)
	(footprint ""
		(layer "F.Cu")
		(at 355.233478 -238.162338 -90)
		(property "Reference" "C1043"
			(at 0 0 270)
			(layer "F.SilkS")
			(hide yes)
			(effects
				(font
					(size 1.27 1.27)
				)
			)
		)
		(property "Value" ""
			(at 0 0 270)
			(layer "F.Fab")
			(effects
				(font
					(size 1.27 1.27)
				)
			)
		)
		(duplicate_pad_numbers_are_jumpers no)
		(fp_line
			(start -0.7874 0.4064)
			(end -0.7874 -0.4064)
			(stroke
				(width 0.1524)
				(type default)
			)
			(layer "F.SilkS")
		)
		(fp_line
			(start 0.7874 0.4064)
			(end -0.7874 0.4064)
			(stroke
				(width 0.1524)
				(type default)
			)
			(layer "F.SilkS")
		)
		(fp_line
			(start -0.7874 -0.4064)
			(end 0.7874 -0.4064)
			(stroke
				(width 0.1524)
				(type default)
			)
			(layer "F.SilkS")
		)
		(fp_line
			(start 0.7874 -0.4064)
			(end 0.7874 0.4064)
			(stroke
				(width 0.1524)
				(type default)
			)
			(layer "F.SilkS")
		)
		(fp_line
			(start -0.67945 0.3048)
			(end -0.67945 -0.305054)
			(stroke
				(width 0.1)
				(type default)
			)
			(layer "F.Fab")
		)
		(fp_line
			(start -0.12065 0.3048)
			(end -0.67945 0.3048)
			(stroke
				(width 0.1)
				(type default)
			)
			(layer "F.Fab")
		)
		(fp_line
			(start 0.120396 0.3048)
			(end 0.120396 0.2794)
			(stroke
				(width 0.1)
				(type default)
			)
			(layer "F.Fab")
		)
		(fp_line
			(start 0.67945 0.3048)
			(end 0.120396 0.3048)
			(stroke
				(width 0.1)
				(type default)
			)
			(layer "F.Fab")
		)
		(fp_line
			(start -0.12065 0.2794)
			(end -0.12065 0.3048)
			(stroke
				(width 0.1)
				(type default)
			)
			(layer "F.Fab")
		)
		(fp_line
			(start 0.120396 0.2794)
			(end -0.12065 0.2794)
			(stroke
				(width 0.1)
				(type default)
			)
			(layer "F.Fab")
		)
		(fp_line
			(start -0.12065 -0.2794)
			(end 0.12065 -0.2794)
			(stroke
				(width 0.1)
				(type default)
			)
			(layer "F.Fab")
		)
		(fp_line
			(start 0.12065 -0.2794)
			(end 0.12065 -0.3048)
			(stroke
				(width 0.1)
				(type default)
			)
			(layer "F.Fab")
		)
		(fp_line
			(start 0.12065 -0.3048)
			(end 0.67945 -0.3048)
			(stroke
				(width 0.1)
				(type default)
			)
			(layer "F.Fab")
		)
		(fp_line
			(start 0.67945 -0.3048)
			(end 0.67945 0.3048)
			(stroke
				(width 0.1)
				(type default)
			)
			(layer "F.Fab")
		)
		(fp_line
			(start -0.67945 -0.305054)
			(end -0.12065 -0.305054)
			(stroke
				(width 0.1)
				(type default)
			)
			(layer "F.Fab")
		)
		(fp_line
			(start -0.12065 -0.305054)
			(end -0.12065 -0.2794)
			(stroke
				(width 0.1)
				(type default)
			)
			(layer "F.Fab")
		)
		(pad "1" smd circle
			(at -0.40005 0 270)
			(size 0 0)
			(layers "F.Cu" "F.Mask" "F.Paste")
			(net "PVCCIN_CPU0")
		)
		(pad "2" smd circle
			(at 0.40005 0 270)
			(size 0 0)
			(layers "F.Cu" "F.Mask" "F.Paste")
			(net "GND")
		)
	)
	(footprint ""
		(layer "F.Cu")
		(at 355.227128 -258.726686 90)
		(property "Reference" "C970"
			(at 0 0 90)
			(layer "F.SilkS")
			(hide yes)
			(effects
				(font
					(size 1.27 1.27)
				)
			)
		)
		(property "Value" ""
			(at 0 0 90)
			(layer "F.Fab")
			(effects
				(font
					(size 1.27 1.27)
				)
			)
		)
		(duplicate_pad_numbers_are_jumpers no)
		(fp_line
			(start 0.7874 -0.4064)
			(end 0.7874 0.4064)
			(stroke
				(width 0.1524)
				(type default)
			)
			(layer "F.SilkS")
		)
		(fp_line
			(start -0.7874 -0.4064)
			(end 0.7874 -0.4064)
			(stroke
				(width 0.1524)
				(type default)
			)
			(layer "F.SilkS")
		)
		(fp_line
			(start 0.7874 0.4064)
			(end -0.7874 0.4064)
			(stroke
				(width 0.1524)
				(type default)
			)
			(layer "F.SilkS")
		)
		(fp_line
			(start -0.7874 0.4064)
			(end -0.7874 -0.4064)
			(stroke
				(width 0.1524)
				(type default)
			)
			(layer "F.SilkS")
		)
		(fp_line
			(start -0.12065 -0.305054)
			(end -0.12065 -0.2794)
			(stroke
				(width 0.1)
				(type default)
			)
			(layer "F.Fab")
		)
		(fp_line
			(start -0.67945 -0.305054)
			(end -0.12065 -0.305054)
			(stroke
				(width 0.1)
				(type default)
			)
			(layer "F.Fab")
		)
		(fp_line
			(start 0.67945 -0.3048)
			(end 0.67945 0.3048)
			(stroke
				(width 0.1)
				(type default)
			)
			(layer "F.Fab")
		)
		(fp_line
			(start 0.12065 -0.3048)
			(end 0.67945 -0.3048)
			(stroke
				(width 0.1)
				(type default)
			)
			(layer "F.Fab")
		)
		(fp_line
			(start 0.12065 -0.2794)
			(end 0.12065 -0.3048)
			(stroke
				(width 0.1)
				(type default)
			)
			(layer "F.Fab")
		)
		(fp_line
			(start -0.12065 -0.2794)
			(end 0.12065 -0.2794)
			(stroke
				(width 0.1)
				(type default)
			)
			(layer "F.Fab")
		)
		(fp_line
			(start 0.120396 0.2794)
			(end -0.12065 0.2794)
			(stroke
				(width 0.1)
				(type default)
			)
			(layer "F.Fab")
		)
		(fp_line
			(start -0.12065 0.2794)
			(end -0.12065 0.3048)
			(stroke
				(width 0.1)
				(type default)
			)
			(layer "F.Fab")
		)
		(fp_line
			(start 0.67945 0.3048)
			(end 0.120396 0.3048)
			(stroke
				(width 0.1)
				(type default)
			)
			(layer "F.Fab")
		)
		(fp_line
			(start 0.120396 0.3048)
			(end 0.120396 0.2794)
			(stroke
				(width 0.1)
				(type default)
			)
			(layer "F.Fab")
		)
		(fp_line
			(start -0.12065 0.3048)
			(end -0.67945 0.3048)
			(stroke
				(width 0.1)
				(type default)
			)
			(layer "F.Fab")
		)
		(fp_line
			(start -0.67945 0.3048)
			(end -0.67945 -0.305054)
			(stroke
				(width 0.1)
				(type default)
			)
			(layer "F.Fab")
		)
		(pad "1" smd circle
			(at -0.40005 0 90)
			(size 0 0)
			(layers "F.Cu" "F.Mask" "F.Paste")
			(net "PVCCIN_CPU0")
		)
		(pad "2" smd circle
			(at 0.40005 0 90)
			(size 0 0)
			(layers "F.Cu" "F.Mask" "F.Paste")
			(net "GND")
		)
	)
)
